(kicad_pcb
	(version 20260206)
	(generator "pcbnew")
	(generator_version "10.0")
	(general
		(thickness 1.6)
		(legacy_teardrops no)
	)
	(paper "A4")
	(title_block
		(title "panther-plus-userver — 13130-1b_20150205.brd")
		(comment 1 "Honey Badger (Wiwynn) / footprints 1350-1351 of 1509")
	)
	(layers
		(0 "F.Cu" signal "TOP")
		(4 "In1.Cu" signal "L2")
		(6 "In2.Cu" signal "L3")
		(8 "In3.Cu" signal "L4")
		(10 "In4.Cu" signal "L5")
		(12 "In5.Cu" signal "L6")
		(14 "In6.Cu" signal "L7")
		(16 "In7.Cu" signal "L8")
		(18 "In8.Cu" signal "L9")
		(20 "In9.Cu" signal "L10")
		(22 "In10.Cu" signal "L11")
		(2 "B.Cu" signal "BOTTOM")
		(9 "F.Adhes" user "F.Adhesive")
		(11 "B.Adhes" user "B.Adhesive")
		(13 "F.Paste" user "Package Geometry/Pastemask Top")
		(15 "B.Paste" user "Package Geometry/Pastemask Bottom")
		(5 "F.SilkS" user "Ref Des/Silkscreen Top")
		(7 "B.SilkS" user "Ref Des/Silkscreen Bottom")
		(1 "F.Mask" user "Board Geometry/Soldermask Top")
		(3 "B.Mask" user "Board Geometry/Soldermask Bottom")
		(17 "Dwgs.User" user "User.Drawings")
		(19 "Cmts.User" user "User.Comments")
		(21 "Eco1.User" user "User.Eco1")
		(23 "Eco2.User" user "User.Eco2")
		(25 "Edge.Cuts" user "Board Geometry/Outline")
		(27 "Margin" user)
		(31 "F.CrtYd" user "Package Geometry/Place Bound Top")
		(29 "B.CrtYd" user "Package Geometry/Place Bound Bottom")
		(35 "F.Fab" user "Ref Des/Assembly Top")
		(33 "B.Fab" user "Ref Des/Assembly Bottom")
	)
	(footprint ""
		(layer "B.Cu")
		(at 46.863 -14.605 -90)
		(property "Reference" "R426"
			(at 0 0 90)
			(layer "B.SilkS")
			(hide yes)
			(effects
				(font
					(size 1.27 1.27)
				)
				(justify mirror)
			)
		)
		(property "Value" "43D2R2F-GP"
			(at -1.7907 -1.1176 270)
			(unlocked yes)
			(layer "B.Fab")
			(hide yes)
			(effects
				(font
					(size 1.016 1.016)
					(thickness 0.1524)
				)
				(justify mirror)
			)
		)
		(property "Device Type" "R402H16"
			(at -1.7907 -2.6416 270)
			(unlocked yes)
			(layer "B.Fab")
			(hide yes)
			(effects
				(font
					(size 1.016 1.016)
					(thickness 0.1524)
				)
				(justify mirror)
			)
		)
		(duplicate_pad_numbers_are_jumpers no)
		(fp_rect
			(start 0.381 0.8382)
			(end -0.381 -0.8382)
			(stroke
				(width 0)
				(type default)
			)
			(fill no)
			(layer "B.CrtYd")
		)
		(fp_rect
			(start 0.381 0.8382)
			(end -0.381 -0.8382)
			(stroke
				(width 0)
				(type default)
			)
			(fill no)
			(layer "B.Fab")
		)
		(pad "1" smd custom
			(at 0 -0.4318 90)
			(size 0.127 0.127)
			(layers "B.Cu" "B.Mask" "B.Paste")
			(net "CLK_100M_PCIE2_REFCLK_DN")
			(options
				(clearance outline)
				(anchor circle)
			)
			(primitives
				(gr_poly
					(pts
						(arc
							(start -0.2032 0.2794)
							(mid -0.239121 0.264521)
							(end -0.254 0.2286)
						)
						(arc
							(start -0.254 -0.2286)
							(mid -0.239121 -0.264521)
							(end -0.2032 -0.2794)
						)
						(arc
							(start 0.2032 -0.2794)
							(mid 0.239121 -0.264521)
							(end 0.254 -0.2286)
						)
						(arc
							(start 0.254 0.2286)
							(mid 0.239121 0.264521)
							(end 0.2032 0.2794)
						)
					)
					(width 0)
					(fill yes)
				)
			)
		)
		(pad "2" smd custom
			(at 0 0.4318 90)
			(size 0.127 0.127)
			(layers "B.Cu" "B.Mask" "B.Paste")
			(net "GND")
			(options
				(clearance outline)
				(anchor circle)
			)
			(primitives
				(gr_poly
					(pts
						(arc
							(start -0.2032 0.2794)
							(mid -0.239121 0.264521)
							(end -0.254 0.2286)
						)
						(arc
							(start -0.254 -0.2286)
							(mid -0.239121 -0.264521)
							(end -0.2032 -0.2794)
						)
						(arc
							(start 0.2032 -0.2794)
							(mid 0.239121 -0.264521)
							(end 0.254 -0.2286)
						)
						(arc
							(start 0.254 0.2286)
							(mid 0.239121 0.264521)
							(end 0.2032 0.2794)
						)
					)
					(width 0)
					(fill yes)
				)
			)
		)
	)
	(footprint ""
		(layer "B.Cu")
		(at 10.850118 -58.699908 90)
		(property "Reference" "NGFF1"
			(at 0 0 90)
			(layer "B.SilkS")
			(hide yes)
			(effects
				(font
					(size 1.27 1.27)
				)
				(justify mirror)
			)
		)
		(property "Value" "SKT-MINI67P-10-GP"
			(at -3.6957 -7.7851 90)
			(unlocked yes)
			(layer "B.Fab")
			(hide yes)
			(effects
				(font
					(size 1.016 1.016)
					(thickness 0.1524)
				)
				(justify mirror)
			)
		)
		(property "Device Type" "80159-4225"
			(at -3.6957 -9.3091 90)
			(unlocked yes)
			(layer "B.Fab")
			(hide yes)
			(effects
				(font
					(size 1.016 1.016)
					(thickness 0.1524)
				)
				(justify mirror)
			)
		)
		(duplicate_pad_numbers_are_jumpers no)
		(fp_poly
			(pts
				(xy 9.24179 -6.1722) (xy 8.73379 -6.6802) (xy 9.74979 -6.6802)
			)
			(stroke
				(width 0)
				(type default)
			)
			(fill yes)
			(layer "B.SilkS")
		)
		(fp_rect
			(start 11.2141 3.175)
			(end -11.2141 -6.1722)
			(stroke
				(width 0)
				(type default)
			)
			(fill no)
			(layer "B.CrtYd")
		)
		(fp_rect
			(start 11.2141 3.175)
			(end -11.2141 -6.1722)
			(stroke
				(width 0)
				(type default)
			)
			(fill no)
			(layer "B.Fab")
		)
		(pad "" np_thru_hole circle
			(at -9.99998 0 270)
			(size 0.254 0.254)
			(drill 1.651)
			(layers "*.Cu" "*.Mask")
			(clearance 1.0541)
			(thermal_gap 1.0541)
		)
		(pad "" np_thru_hole circle
			(at 9.99998 0 270)
			(size 0.254 0.254)
			(drill 1.1176)
			(layers "*.Cu" "*.Mask")
			(clearance 0.7874)
			(thermal_gap 0.7874)
		)
		(pad "1" smd rect
			(at 9.249918 -5.275072 270)
			(size 0.3048 1.5494)
			(layers "B.Cu" "B.Mask" "B.Paste")
			(net "NGFF_PRESENT_R#")
		)
		(pad "2" smd rect
			(at 8.999982 2.275078 270)
			(size 0.3048 1.5494)
			(layers "B.Cu" "B.Mask" "B.Paste")
			(net "P3V3")
		)
		(pad "3" smd rect
			(at 8.750046 -5.275072 270)
			(size 0.3048 1.5494)
			(layers "B.Cu" "B.Mask" "B.Paste")
			(net "GND")
		)
		(pad "4" smd rect
			(at 8.50011 2.275078 270)
			(size 0.3048 1.5494)
			(layers "B.Cu" "B.Mask" "B.Paste")
			(net "P3V3")
		)
		(pad "5" smd rect
			(at 8.24992 -5.275072 270)
			(size 0.3048 1.5494)
			(layers "B.Cu" "B.Mask" "B.Paste")
			(net "P2E_CPU_NGFF_C_RX_DN15")
		)
		(pad "6" smd rect
			(at 7.999984 2.275078 270)
			(size 0.3048 1.5494)
			(layers "B.Cu" "B.Mask" "B.Paste")
			(net "Net_1393")
		)
		(pad "7" smd rect
			(at 7.750048 -5.275072 270)
			(size 0.3048 1.5494)
			(layers "B.Cu" "B.Mask" "B.Paste")
			(net "P2E_CPU_NGFF_C_RX_DP15")
		)
		(pad "8" smd rect
			(at 7.500112 2.275078 270)
			(size 0.3048 1.5494)
			(layers "B.Cu" "B.Mask" "B.Paste")
			(net "Net_1392")
		)
		(pad "9" smd rect
			(at 7.249922 -5.275072 270)
			(size 0.3048 1.5494)
			(layers "B.Cu" "B.Mask" "B.Paste")
			(net "GND")
		)
		(pad "10" smd rect
			(at 6.999986 2.275078 270)
			(size 0.3048 1.5494)
			(layers "B.Cu" "B.Mask" "B.Paste")
			(net "LED_NGFF_DAS")
		)
		(pad "11" smd rect
			(at 6.75005 -5.275072 270)
			(size 0.3048 1.5494)
			(layers "B.Cu" "B.Mask" "B.Paste")
			(net "P2E_CPU_NGFF_TX_DN15")
		)
		(pad "12" smd rect
			(at 6.500114 2.275078 270)
			(size 0.3048 1.5494)
			(layers "B.Cu" "B.Mask" "B.Paste")
			(net "P3V3")
		)
		(pad "13" smd rect
			(at 6.249924 -5.275072 270)
			(size 0.3048 1.5494)
			(layers "B.Cu" "B.Mask" "B.Paste")
			(net "P2E_CPU_NGFF_TX_DP15")
		)
		(pad "14" smd rect
			(at 5.999988 2.275078 270)
			(size 0.3048 1.5494)
			(layers "B.Cu" "B.Mask" "B.Paste")
			(net "P3V3")
		)
		(pad "15" smd rect
			(at 5.750052 -5.275072 270)
			(size 0.3048 1.5494)
			(layers "B.Cu" "B.Mask" "B.Paste")
			(net "GND")
		)
		(pad "16" smd rect
			(at 5.500116 2.275078 270)
			(size 0.3048 1.5494)
			(layers "B.Cu" "B.Mask" "B.Paste")
			(net "P3V3")
		)
		(pad "17" smd rect
			(at 5.249926 -5.275072 270)
			(size 0.3048 1.5494)
			(layers "B.Cu" "B.Mask" "B.Paste")
			(net "P2E_CPU_NGFF_C_RX_DN14")
		)
		(pad "18" smd rect
			(at 4.99999 2.275078 270)
			(size 0.3048 1.5494)
			(layers "B.Cu" "B.Mask" "B.Paste")
			(net "P3V3")
		)
		(pad "19" smd rect
			(at 4.750054 -5.275072 270)
			(size 0.3048 1.5494)
			(layers "B.Cu" "B.Mask" "B.Paste")
			(net "P2E_CPU_NGFF_C_RX_DP14")
		)
		(pad "20" smd rect
			(at 4.500118 2.275078 270)
			(size 0.3048 1.5494)
			(layers "B.Cu" "B.Mask" "B.Paste")
			(net "Net_1391")
		)
		(pad "21" smd rect
			(at 4.249928 -5.275072 270)
			(size 0.3048 1.5494)
			(layers "B.Cu" "B.Mask" "B.Paste")
			(net "GND")
		)
		(pad "22" smd rect
			(at 3.999992 2.275078 270)
			(size 0.3048 1.5494)
			(layers "B.Cu" "B.Mask" "B.Paste")
			(net "Net_1390")
		)
		(pad "23" smd rect
			(at 3.750056 -5.275072 270)
			(size 0.3048 1.5494)
			(layers "B.Cu" "B.Mask" "B.Paste")
			(net "P2E_CPU_NGFF_TX_DN14")
		)
		(pad "24" smd rect
			(at 3.50012 2.275078 270)
			(size 0.3048 1.5494)
			(layers "B.Cu" "B.Mask" "B.Paste")
			(net "Net_1389")
		)
		(pad "25" smd rect
			(at 3.24993 -5.275072 270)
			(size 0.3048 1.5494)
			(layers "B.Cu" "B.Mask" "B.Paste")
			(net "P2E_CPU_NGFF_TX_DP14")
		)
		(pad "26" smd rect
			(at 2.999994 2.275078 270)
			(size 0.3048 1.5494)
			(layers "B.Cu" "B.Mask" "B.Paste")
			(net "Net_1388")
		)
		(pad "27" smd rect
			(at 2.750058 -5.275072 270)
			(size 0.3048 1.5494)
			(layers "B.Cu" "B.Mask" "B.Paste")
			(net "GND")
		)
		(pad "28" smd rect
			(at 2.500122 2.275078 270)
			(size 0.3048 1.5494)
			(layers "B.Cu" "B.Mask" "B.Paste")
			(net "Net_1387")
		)
		(pad "29" smd rect
			(at 2.249932 -5.275072 270)
			(size 0.3048 1.5494)
			(layers "B.Cu" "B.Mask" "B.Paste")
			(net "P2E_CPU_NGFF_C_RX_DN13")
		)
		(pad "30" smd rect
			(at 1.999996 2.275078 270)
			(size 0.3048 1.5494)
			(layers "B.Cu" "B.Mask" "B.Paste")
			(net "Net_1386")
		)
		(pad "31" smd rect
			(at 1.75006 -5.275072 270)
			(size 0.3048 1.5494)
			(layers "B.Cu" "B.Mask" "B.Paste")
			(net "P2E_CPU_NGFF_C_RX_DP13")
		)
		(pad "32" smd rect
			(at 1.500124 2.275078 270)
			(size 0.3048 1.5494)
			(layers "B.Cu" "B.Mask" "B.Paste")
			(net "Net_1385")
		)
		(pad "33" smd rect
			(at 1.249934 -5.275072 270)
			(size 0.3048 1.5494)
			(layers "B.Cu" "B.Mask" "B.Paste")
			(net "GND")
		)
		(pad "34" smd rect
			(at 0.999998 2.275078 270)
			(size 0.3048 1.5494)
			(layers "B.Cu" "B.Mask" "B.Paste")
			(net "Net_1384")
		)
		(pad "35" smd rect
			(at 0.750062 -5.275072 270)
			(size 0.3048 1.5494)
			(layers "B.Cu" "B.Mask" "B.Paste")
			(net "P2E_CPU_NGFF_TX_DN13")
		)
		(pad "36" smd rect
			(at 0.500126 2.275078 270)
			(size 0.3048 1.5494)
			(layers "B.Cu" "B.Mask" "B.Paste")
			(net "Net_1383")
		)
		(pad "37" smd rect
			(at 0.249936 -5.275072 270)
			(size 0.3048 1.5494)
			(layers "B.Cu" "B.Mask" "B.Paste")
			(net "P2E_CPU_NGFF_TX_DP13")
		)
		(pad "38" smd rect
			(at 0 2.275078 270)
			(size 0.3048 1.5494)
			(layers "B.Cu" "B.Mask" "B.Paste")
			(net "Net_1382")
		)
		(pad "39" smd rect
			(at -0.249936 -5.275072 270)
			(size 0.3048 1.5494)
			(layers "B.Cu" "B.Mask" "B.Paste")
			(net "GND")
		)
		(pad "40" smd rect
			(at -0.500126 2.275078 270)
			(size 0.3048 1.5494)
			(layers "B.Cu" "B.Mask" "B.Paste")
			(net "Net_1381")
		)
		(pad "41" smd rect
			(at -0.750062 -5.275072 270)
			(size 0.3048 1.5494)
			(layers "B.Cu" "B.Mask" "B.Paste")
			(net "P2E_CPU_NGFF_C_RX_DN12")
		)
		(pad "42" smd rect
			(at -0.999998 2.275078 270)
			(size 0.3048 1.5494)
			(layers "B.Cu" "B.Mask" "B.Paste")
			(net "Net_1380")
		)
		(pad "43" smd rect
			(at -1.249934 -5.275072 270)
			(size 0.3048 1.5494)
			(layers "B.Cu" "B.Mask" "B.Paste")
			(net "P2E_CPU_NGFF_C_RX_DP12")
		)
		(pad "44" smd rect
			(at -1.500124 2.275078 270)
			(size 0.3048 1.5494)
			(layers "B.Cu" "B.Mask" "B.Paste")
			(net "Net_1379")
		)
		(pad "45" smd rect
			(at -1.75006 -5.275072 270)
			(size 0.3048 1.5494)
			(layers "B.Cu" "B.Mask" "B.Paste")
			(net "GND")
		)
		(pad "46" smd rect
			(at -1.999996 2.275078 270)
			(size 0.3048 1.5494)
			(layers "B.Cu" "B.Mask" "B.Paste")
			(net "Net_1378")
		)
		(pad "47" smd rect
			(at -2.249932 -5.275072 270)
			(size 0.3048 1.5494)
			(layers "B.Cu" "B.Mask" "B.Paste")
			(net "P2E_CPU_NGFF_TX_DN12")
		)
		(pad "48" smd rect
			(at -2.500122 2.275078 270)
			(size 0.3048 1.5494)
			(layers "B.Cu" "B.Mask" "B.Paste")
			(net "Net_1377")
		)
		(pad "49" smd rect
			(at -2.750058 -5.275072 270)
			(size 0.3048 1.5494)
			(layers "B.Cu" "B.Mask" "B.Paste")
			(net "P2E_CPU_NGFF_TX_DP12")
		)
		(pad "50" smd rect
			(at -2.999994 2.275078 270)
			(size 0.3048 1.5494)
			(layers "B.Cu" "B.Mask" "B.Paste")
			(net "RST_PCIE_PCH_DEV_R#")
		)
		(pad "51" smd rect
			(at -3.24993 -5.275072 270)
			(size 0.3048 1.5494)
			(layers "B.Cu" "B.Mask" "B.Paste")
			(net "GND")
		)
		(pad "52" smd rect
			(at -3.50012 2.275078 270)
			(size 0.3048 1.5494)
			(layers "B.Cu" "B.Mask" "B.Paste")
			(net "Net_1376")
		)
		(pad "53" smd rect
			(at -3.750056 -5.275072 270)
			(size 0.3048 1.5494)
			(layers "B.Cu" "B.Mask" "B.Paste")
			(net "CLK_100M_CLKBUFF_NGFF_DN")
		)
		(pad "54" smd rect
			(at -3.999992 2.275078 270)
			(size 0.3048 1.5494)
			(layers "B.Cu" "B.Mask" "B.Paste")
			(net "Net_1374")
		)
		(pad "55" smd rect
			(at -4.249928 -5.275072 270)
			(size 0.3048 1.5494)
			(layers "B.Cu" "B.Mask" "B.Paste")
			(net "CLK_100M_CLKBUFF_NGFF_DP")
		)
		(pad "56" smd rect
			(at -4.500118 2.275078 270)
			(size 0.3048 1.5494)
			(layers "B.Cu" "B.Mask" "B.Paste")
			(net "Net_1373")
		)
		(pad "57" smd rect
			(at -4.750054 -5.275072 270)
			(size 0.3048 1.5494)
			(layers "B.Cu" "B.Mask" "B.Paste")
			(net "GND")
		)
		(pad "58" smd rect
			(at -4.99999 2.275078 270)
			(size 0.3048 1.5494)
			(layers "B.Cu" "B.Mask" "B.Paste")
			(net "Net_1372")
		)
		(pad "67" smd rect
			(at -7.249922 -5.275072 270)
			(size 0.3048 1.5494)
			(layers "B.Cu" "B.Mask" "B.Paste")
			(net "Net_1371")
		)
		(pad "68" smd rect
			(at -7.500112 2.275078 270)
			(size 0.3048 1.5494)
			(layers "B.Cu" "B.Mask" "B.Paste")
			(net "PMU_SUS_CLK")
		)
		(pad "69" smd rect
			(at -7.750048 -5.275072 270)
			(size 0.3048 1.5494)
			(layers "B.Cu" "B.Mask" "B.Paste")
			(net "PEDET_SEL")
		)
		(pad "70" smd rect
			(at -7.999984 2.275078 270)
			(size 0.3048 1.5494)
			(layers "B.Cu" "B.Mask" "B.Paste")
			(net "P3V3")
		)
		(pad "71" smd rect
			(at -8.24992 -5.275072 270)
			(size 0.3048 1.5494)
			(layers "B.Cu" "B.Mask" "B.Paste")
			(net "GND")
		)
		(pad "72" smd rect
			(at -8.50011 2.275078 270)
			(size 0.3048 1.5494)
			(layers "B.Cu" "B.Mask" "B.Paste")
			(net "P3V3")
		)
		(pad "73" smd rect
			(at -8.750046 -5.275072 270)
			(size 0.3048 1.5494)
			(layers "B.Cu" "B.Mask" "B.Paste")
			(net "GND")
		)
		(pad "74" smd rect
			(at -8.999982 2.275078 270)
			(size 0.3048 1.5494)
			(layers "B.Cu" "B.Mask" "B.Paste")
			(net "P3V3")
		)
		(pad "75" smd rect
			(at -9.249918 -5.275072 270)
			(size 0.3048 1.5494)
			(layers "B.Cu" "B.Mask" "B.Paste")
			(net "GND")
		)
		(pad "76" smd rect
			(at 10.349992 -4.500118 270)
			(size 1.1938 2.7432)
			(layers "B.Cu" "B.Mask" "B.Paste")
			(net "GND")
		)
		(pad "77" smd rect
			(at -10.349992 -4.500118 270)
			(size 1.1938 2.7432)
			(layers "B.Cu" "B.Mask" "B.Paste")
			(net "GND")
		)
		(zone
			(layers "F.Cu" "B.Cu" "In1.Cu" "In2.Cu" "In3.Cu" "In4.Cu" "In5.Cu" "In6.Cu"
				"In7.Cu" "In8.Cu" "In9.Cu" "In10.Cu"
			)
			(hatch none 0.5)
			(connect_pads
				(clearance 0)
			)
			(min_thickness 0.25)
			(keepout
				(tracks not_allowed)
				(vias allowed)
				(pads allowed)
				(copperpour not_allowed)
				(footprints allowed)
			)
			(placement
				(enabled no)
				(sheetname "")
			)
			(fill
				(thermal_gap 0.5)
				(thermal_bridge_width 0.5)
				(island_removal_mode 0)
			)
			(polygon
				(pts
					(arc
						(start 11.713718 -68.699888)
						(mid 9.986518 -68.699888)
						(end 11.713718 -68.699888)
					)
				)
			)
		)
		(zone
			(layers "F.Cu" "B.Cu" "In1.Cu" "In2.Cu" "In3.Cu" "In4.Cu" "In5.Cu" "In6.Cu"
				"In7.Cu" "In8.Cu" "In9.Cu" "In10.Cu"
			)
			(hatch none 0.5)
			(connect_pads
				(clearance 0)
			)
			(min_thickness 0.25)
			(keepout
				(tracks not_allowed)
				(vias allowed)
				(pads allowed)
				(copperpour not_allowed)
				(footprints allowed)
			)
			(placement
				(enabled no)
				(sheetname "")
			)
			(fill
				(thermal_gap 0.5)
				(thermal_bridge_width 0.5)
				(island_removal_mode 0)
			)
			(polygon
				(pts
					(arc
						(start 11.980418 -48.699928)
						(mid 9.719818 -48.699928)
						(end 11.980418 -48.699928)
					)
				)
			)
		)
		(zone
			(layer "B.Cu")
			(hatch none 0.5)
			(connect_pads
				(clearance 0)
			)
			(min_thickness 0.25)
			(keepout
				(tracks allowed)
				(vias not_allowed)
				(pads allowed)
				(copperpour not_allowed)
				(footprints allowed)
			)
			(placement
				(enabled no)
				(sheetname "")
			)
			(fill
				(thermal_gap 0.5)
				(thermal_bridge_width 0.5)
				(island_removal_mode 0)
			)
			(polygon
				(pts
					(xy 6.349746 -68.102226) (xy 6.857746 -68.102226) (xy 6.857746 -53.797454) (xy 6.349746 -53.797454)
				)
			)
		)
		(zone
			(layer "B.Cu")
			(hatch none 0.5)
			(connect_pads
				(clearance 0)
			)
			(min_thickness 0.25)
			(keepout
				(tracks allowed)
				(vias not_allowed)
				(pads allowed)
				(copperpour not_allowed)
				(footprints allowed)
			)
			(placement
				(enabled no)
				(sheetname "")
			)
			(fill
				(thermal_gap 0.5)
				(thermal_bridge_width 0.5)
				(island_removal_mode 0)
			)
			(polygon
				(pts
					(xy 6.349746 -51.602386) (xy 6.857746 -51.602386) (xy 6.857746 -49.29759) (xy 6.349746 -49.29759)
				)
			)
		)
		(zone
			(layer "B.Cu")
			(hatch none 0.5)
			(connect_pads
				(clearance 0)
			)
			(min_thickness 0.25)
			(keepout
				(tracks allowed)
				(vias not_allowed)
				(pads allowed)
				(copperpour not_allowed)
				(footprints allowed)
			)
			(placement
				(enabled no)
				(sheetname "")
			)
			(fill
				(thermal_gap 0.5)
				(thermal_bridge_width 0.5)
				(island_removal_mode 0)
			)
			(polygon
				(pts
					(xy 11.842496 -67.85229) (xy 12.350496 -67.85229) (xy 12.350496 -53.547518) (xy 11.842496 -53.547518)
				)
			)
		)
		(zone
			(layer "B.Cu")
			(hatch none 0.5)
			(connect_pads
				(clearance 0)
			)
			(min_thickness 0.25)
			(keepout
				(tracks allowed)
				(vias not_allowed)
				(pads allowed)
				(copperpour not_allowed)
				(footprints allowed)
			)
			(placement
				(enabled no)
				(sheetname "")
			)
			(fill
				(thermal_gap 0.5)
				(thermal_bridge_width 0.5)
				(island_removal_mode 0)
			)
			(polygon
				(pts
					(xy 11.842496 -51.352196) (xy 12.350496 -51.352196) (xy 12.350496 -49.547526) (xy 11.842496 -49.547526)
				)
			)
		)
	)
)
